# T6G (Grand Teton) — schematic netlist excerpt (pin names and nets, part order shuffled) for the footprints in the layout excerpt that follows; sources: Cadence DE-HDL packaged netlist, KiCad conversion of 04192023_DAF0TMB3IC0_F0TG_MB_C_brd_V02_OCP.brd

C2468  Q_CAP  22UF 4V 20% X6S  pkg C0402  page 74 : A = PVDDCR_SOC_P1 ; B = GND
PC603_2  Q_CAP  22UF 4V 20% X6S  pkg C0805  page 198 : A = PVDDCR_SOC_P0 ; B = GND
C2584  Q_CAP  22UF 4V 20% X6S  pkg C0402  page 70 : A = PVDDCR_SOC_P0 ; B = GND

(kicad_pcb
	(version 20260206)
	(generator "pcbnew")
	(generator_version "10.0")
	(general
		(thickness 1.6)
		(legacy_teardrops no)
	)
	(paper "A4")
	(title_block
		(title "04192023_DAF0TMB3IC0_F0TG_MB_C_brd_V02_OCP.brd")
		(comment 1 "Grand Teton / footprints 6083-6085 of 8354")
	)
	(layers
		(0 "F.Cu" signal "TOP")
		(4 "In1.Cu" signal "GND")
		(6 "In2.Cu" signal "IN1")
		(8 "In3.Cu" signal "GND1")
		(10 "In4.Cu" signal "IN2")
		(12 "In5.Cu" signal "GND2")
		(14 "In6.Cu" signal "IN3")
		(16 "In7.Cu" signal "GND3")
		(18 "In8.Cu" signal "VCC")
		(20 "In9.Cu" signal "VCC1")
		(22 "In10.Cu" signal "GND4")
		(24 "In11.Cu" signal "IN4")
		(26 "In12.Cu" signal "GND5")
		(28 "In13.Cu" signal "IN5")
		(30 "In14.Cu" signal "GND6")
		(32 "In15.Cu" signal "IN6")
		(34 "In16.Cu" signal "GND7")
		(2 "B.Cu" signal "BOTTOM")
		(9 "F.Adhes" user "F.Adhesive")
		(11 "B.Adhes" user "B.Adhesive")
		(13 "F.Paste" user "Package Geometry/Pastemask Top")
		(15 "B.Paste" user "Package Geometry/Pastemask Bottom")
		(5 "F.SilkS" user "Ref Des/Silkscreen Top")
		(7 "B.SilkS" user "Ref Des/Silkscreen Bottom")
		(1 "F.Mask" user "Board Geometry/Soldermask Top")
		(3 "B.Mask" user "Board Geometry/Soldermask Bottom")
		(17 "Dwgs.User" user "User.Drawings")
		(19 "Cmts.User" user "User.Comments")
		(21 "Eco1.User" user "User.Eco1")
		(23 "Eco2.User" user "User.Eco2")
		(25 "Edge.Cuts" user "Board Geometry/Outline")
		(27 "Margin" user)
		(31 "F.CrtYd" user "Package Geometry/Place Bound Top")
		(29 "B.CrtYd" user "Package Geometry/Place Bound Bottom")
		(35 "F.Fab" user "Ref Des/Assembly Top")
		(33 "B.Fab" user "Ref Des/Assembly Bottom")
	)
	(footprint ""
		(layer "B.Cu")
		(at 121.706386 -252.543564)
		(property "Reference" "C2468"
			(at 0 0 0)
			(layer "B.SilkS")
			(hide yes)
			(effects
				(font
					(size 1.27 1.27)
				)
				(justify mirror)
			)
		)
		(property "Value" ""
			(at 0 0 0)
			(layer "B.Fab")
			(effects
				(font
					(size 1.27 1.27)
				)
				(justify mirror)
			)
		)
		(duplicate_pad_numbers_are_jumpers no)
		(fp_line
			(start -0.7874 -0.4064)
			(end -0.7874 0.4064)
			(stroke
				(width 0.1524)
				(type default)
			)
			(layer "B.SilkS")
		)
		(fp_line
			(start -0.7874 0.4064)
			(end 0.7874 0.4064)
			(stroke
				(width 0.1524)
				(type default)
			)
			(layer "B.SilkS")
		)
		(fp_line
			(start 0.7874 -0.4064)
			(end -0.7874 -0.4064)
			(stroke
				(width 0.1524)
				(type default)
			)
			(layer "B.SilkS")
		)
		(fp_line
			(start 0.7874 0.4064)
			(end 0.7874 -0.4064)
			(stroke
				(width 0.1524)
				(type default)
			)
			(layer "B.SilkS")
		)
		(fp_line
			(start -0.67945 -0.3048)
			(end -0.67945 0.3048)
			(stroke
				(width 0.1)
				(type default)
			)
			(layer "B.Fab")
		)
		(fp_line
			(start -0.67945 0.3048)
			(end -0.120396 0.3048)
			(stroke
				(width 0.1)
				(type default)
			)
			(layer "B.Fab")
		)
		(fp_line
			(start -0.12065 -0.3048)
			(end -0.67945 -0.3048)
			(stroke
				(width 0.1)
				(type default)
			)
			(layer "B.Fab")
		)
		(fp_line
			(start -0.12065 -0.2794)
			(end -0.12065 -0.3048)
			(stroke
				(width 0.1)
				(type default)
			)
			(layer "B.Fab")
		)
		(fp_line
			(start -0.120396 0.2794)
			(end 0.12065 0.2794)
			(stroke
				(width 0.1)
				(type default)
			)
			(layer "B.Fab")
		)
		(fp_line
			(start -0.120396 0.3048)
			(end -0.120396 0.2794)
			(stroke
				(width 0.1)
				(type default)
			)
			(layer "B.Fab")
		)
		(fp_line
			(start 0.12065 -0.305054)
			(end 0.12065 -0.2794)
			(stroke
				(width 0.1)
				(type default)
			)
			(layer "B.Fab")
		)
		(fp_line
			(start 0.12065 -0.2794)
			(end -0.12065 -0.2794)
			(stroke
				(width 0.1)
				(type default)
			)
			(layer "B.Fab")
		)
		(fp_line
			(start 0.12065 0.2794)
			(end 0.12065 0.3048)
			(stroke
				(width 0.1)
				(type default)
			)
			(layer "B.Fab")
		)
		(fp_line
			(start 0.12065 0.3048)
			(end 0.67945 0.3048)
			(stroke
				(width 0.1)
				(type default)
			)
			(layer "B.Fab")
		)
		(fp_line
			(start 0.67945 -0.305054)
			(end 0.12065 -0.305054)
			(stroke
				(width 0.1)
				(type default)
			)
			(layer "B.Fab")
		)
		(fp_line
			(start 0.67945 0.3048)
			(end 0.67945 -0.305054)
			(stroke
				(width 0.1)
				(type default)
			)
			(layer "B.Fab")
		)
		(pad "1" smd circle
			(at 0.40005 0 180)
			(size 0 0)
			(layers "B.Cu" "B.Mask" "B.Paste")
			(net "PVDDCR_SOC_P1")
		)
		(pad "2" smd circle
			(at -0.40005 0 180)
			(size 0 0)
			(layers "B.Cu" "B.Mask" "B.Paste")
			(net "GND")
		)
	)
	(footprint ""
		(layer "B.Cu")
		(at 373.329454 -259.729986)
		(property "Reference" "C2584"
			(at 0 0 0)
			(layer "B.SilkS")
			(hide yes)
			(effects
				(font
					(size 1.27 1.27)
				)
				(justify mirror)
			)
		)
		(property "Value" ""
			(at 0 0 0)
			(layer "B.Fab")
			(effects
				(font
					(size 1.27 1.27)
				)
				(justify mirror)
			)
		)
		(duplicate_pad_numbers_are_jumpers no)
		(fp_line
			(start -0.7874 -0.4064)
			(end -0.7874 0.4064)
			(stroke
				(width 0.1524)
				(type default)
			)
			(layer "B.SilkS")
		)
		(fp_line
			(start -0.7874 0.4064)
			(end 0.7874 0.4064)
			(stroke
				(width 0.1524)
				(type default)
			)
			(layer "B.SilkS")
		)
		(fp_line
			(start 0.7874 -0.4064)
			(end -0.7874 -0.4064)
			(stroke
				(width 0.1524)
				(type default)
			)
			(layer "B.SilkS")
		)
		(fp_line
			(start 0.7874 0.4064)
			(end 0.7874 -0.4064)
			(stroke
				(width 0.1524)
				(type default)
			)
			(layer "B.SilkS")
		)
		(fp_line
			(start -0.67945 -0.3048)
			(end -0.67945 0.3048)
			(stroke
				(width 0.1)
				(type default)
			)
			(layer "B.Fab")
		)
		(fp_line
			(start -0.67945 0.3048)
			(end -0.120396 0.3048)
			(stroke
				(width 0.1)
				(type default)
			)
			(layer "B.Fab")
		)
		(fp_line
			(start -0.12065 -0.3048)
			(end -0.67945 -0.3048)
			(stroke
				(width 0.1)
				(type default)
			)
			(layer "B.Fab")
		)
		(fp_line
			(start -0.12065 -0.2794)
			(end -0.12065 -0.3048)
			(stroke
				(width 0.1)
				(type default)
			)
			(layer "B.Fab")
		)
		(fp_line
			(start -0.120396 0.2794)
			(end 0.12065 0.2794)
			(stroke
				(width 0.1)
				(type default)
			)
			(layer "B.Fab")
		)
		(fp_line
			(start -0.120396 0.3048)
			(end -0.120396 0.2794)
			(stroke
				(width 0.1)
				(type default)
			)
			(layer "B.Fab")
		)
		(fp_line
			(start 0.12065 -0.305054)
			(end 0.12065 -0.2794)
			(stroke
				(width 0.1)
				(type default)
			)
			(layer "B.Fab")
		)
		(fp_line
			(start 0.12065 -0.2794)
			(end -0.12065 -0.2794)
			(stroke
				(width 0.1)
				(type default)
			)
			(layer "B.Fab")
		)
		(fp_line
			(start 0.12065 0.2794)
			(end 0.12065 0.3048)
			(stroke
				(width 0.1)
				(type default)
			)
			(layer "B.Fab")
		)
		(fp_line
			(start 0.12065 0.3048)
			(end 0.67945 0.3048)
			(stroke
				(width 0.1)
				(type default)
			)
			(layer "B.Fab")
		)
		(fp_line
			(start 0.67945 -0.305054)
			(end 0.12065 -0.305054)
			(stroke
				(width 0.1)
				(type default)
			)
			(layer "B.Fab")
		)
		(fp_line
			(start 0.67945 0.3048)
			(end 0.67945 -0.305054)
			(stroke
				(width 0.1)
				(type default)
			)
			(layer "B.Fab")
		)
		(pad "1" smd circle
			(at 0.40005 0 180)
			(size 0 0)
			(layers "B.Cu" "B.Mask" "B.Paste")
			(net "PVDDCR_SOC_P0")
		)
		(pad "2" smd circle
			(at -0.40005 0 180)
			(size 0 0)
			(layers "B.Cu" "B.Mask" "B.Paste")
			(net "GND")
		)
	)
	(footprint ""
		(layer "B.Cu")
		(at 403.17928 -178.77282 90)
		(property "Reference" "PC603_2"
			(at 0 0 90)
			(layer "B.SilkS")
			(hide yes)
			(effects
				(font
					(size 1.27 1.27)
				)
				(justify mirror)
			)
		)
		(property "Value" ""
			(at 0 0 90)
			(layer "B.Fab")
			(effects
				(font
					(size 1.27 1.27)
				)
				(justify mirror)
			)
		)
		(duplicate_pad_numbers_are_jumpers no)
		(fp_line
			(start 1.524 -0.762)
			(end -1.524 -0.762)
			(stroke
				(width 0.1524)
				(type default)
			)
			(layer "B.SilkS")
		)
		(fp_line
			(start -1.524 -0.762)
			(end -1.524 0.762)
			(stroke
				(width 0.1524)
				(type default)
			)
			(layer "B.SilkS")
		)
		(fp_line
			(start 1.524 0.762)
			(end 1.524 -0.762)
			(stroke
				(width 0.1524)
				(type default)
			)
			(layer "B.SilkS")
		)
		(fp_line
			(start -1.524 0.762)
			(end 1.524 0.762)
			(stroke
				(width 0.1524)
				(type default)
			)
			(layer "B.SilkS")
		)
		(fp_line
			(start 1.1049 -0.724916)
			(end 1.1049 0.724916)
			(stroke
				(width 0.1)
				(type default)
			)
			(layer "B.Fab")
		)
		(fp_line
			(start -1.1049 -0.724916)
			(end 1.1049 -0.724916)
			(stroke
				(width 0.1)
				(type default)
			)
			(layer "B.Fab")
		)
		(fp_line
			(start 1.1049 0.724916)
			(end -1.1049 0.724916)
			(stroke
				(width 0.1)
				(type default)
			)
			(layer "B.Fab")
		)
		(fp_line
			(start -1.1049 0.724916)
			(end -1.1049 -0.724916)
			(stroke
				(width 0.1)
				(type default)
			)
			(layer "B.Fab")
		)
		(pad "1" smd rect
			(at 0.889 0 90)
			(size 1.016 1.27)
			(layers "B.Cu" "B.Mask" "B.Paste")
			(net "PVDDCR_SOC_P0")
		)
		(pad "2" smd rect
			(at -0.889 0 90)
			(size 1.016 1.27)
			(layers "B.Cu" "B.Mask" "B.Paste")
			(net "GND")
		)
	)
)
